(kicad_pcb
	(version 20260206)
	(generator "pcbnew")
	(generator_version "10.0")
	(general
		(thickness 1.6)
		(legacy_teardrops no)
	)
	(paper "A4")
	(title_block
		(title "baseboard — 13948-1b.1110WZS1818.brd")
		(comment 1 "Honey Badger (Wiwynn) / footprints 1008-1015 of 2523")
	)
	(layers
		(0 "F.Cu" signal "TOP")
		(4 "In1.Cu" signal "L2GND")
		(6 "In2.Cu" signal "L3")
		(8 "In3.Cu" signal "L4VCC")
		(10 "In4.Cu" signal "L5VCC")
		(12 "In5.Cu" signal "L6")
		(14 "In6.Cu" signal "L7GND")
		(2 "B.Cu" signal "BOTTOM")
		(9 "F.Adhes" user "F.Adhesive")
		(11 "B.Adhes" user "B.Adhesive")
		(13 "F.Paste" user "Package Geometry/Pastemask Top")
		(15 "B.Paste" user "Package Geometry/Pastemask Bottom")
		(5 "F.SilkS" user "Ref Des/Silkscreen Top")
		(7 "B.SilkS" user "Ref Des/Silkscreen Bottom")
		(1 "F.Mask" user "Board Geometry/Soldermask Top")
		(3 "B.Mask" user "Board Geometry/Soldermask Bottom")
		(17 "Dwgs.User" user "User.Drawings")
		(19 "Cmts.User" user "User.Comments")
		(21 "Eco1.User" user "User.Eco1")
		(23 "Eco2.User" user "User.Eco2")
		(25 "Edge.Cuts" user "Board Geometry/Outline")
		(27 "Margin" user)
		(31 "F.CrtYd" user "Package Geometry/Place Bound Top")
		(29 "B.CrtYd" user "Package Geometry/Place Bound Bottom")
		(35 "F.Fab" user "Ref Des/Assembly Top")
		(33 "B.Fab" user "Ref Des/Assembly Bottom")
	)
	(footprint ""
		(layer "F.Cu")
		(at 273.499072 -55.936896 -90)
		(property "Reference" "PQ2"
			(at 0 0 270)
			(layer "F.SilkS")
			(hide yes)
			(effects
				(font
					(size 1.27 1.27)
				)
			)
		)
		(property "Value" "2N7002A-7-GP"
			(at 0.127 -8.9662 270)
			(unlocked yes)
			(layer "F.Fab")
			(hide yes)
			(effects
				(font
					(size 1.016 1.016)
					(thickness 0.1524)
				)
			)
		)
		(property "Device Type" "SOT23DGS2D4H48"
			(at 0.127 -10.4902 270)
			(unlocked yes)
			(layer "F.Fab")
			(hide yes)
			(effects
				(font
					(size 1.016 1.016)
					(thickness 0.1524)
				)
			)
		)
		(duplicate_pad_numbers_are_jumpers no)
		(fp_line
			(start -1.651 1.778)
			(end 1.651 1.778)
			(stroke
				(width 0.1524)
				(type default)
			)
			(layer "F.SilkS")
		)
		(fp_line
			(start 1.651 1.778)
			(end 1.651 -1.778)
			(stroke
				(width 0.1524)
				(type default)
			)
			(layer "F.SilkS")
		)
		(fp_line
			(start -1.651 -1.778)
			(end -1.651 1.778)
			(stroke
				(width 0.1524)
				(type default)
			)
			(layer "F.SilkS")
		)
		(fp_line
			(start 1.651 -1.778)
			(end -1.651 -1.778)
			(stroke
				(width 0.1524)
				(type default)
			)
			(layer "F.SilkS")
		)
		(fp_poly
			(pts
				(xy -1.778 1.8796) (xy -1.778 -1.8796) (xy 1.778 -1.8796) (xy 1.778 1.8796)
			)
			(stroke
				(width 0)
				(type default)
			)
			(fill no)
			(layer "F.CrtYd")
		)
		(fp_poly
			(pts
				(xy -1.778 1.8796) (xy -1.778 -1.8796) (xy 1.778 -1.8796) (xy 1.778 1.8796)
			)
			(stroke
				(width 0)
				(type default)
			)
			(fill no)
			(layer "F.Fab")
		)
		(pad "D" smd custom
			(at 0 -0.9525 270)
			(size 0.1905 0.1905)
			(layers "F.Cu" "F.Mask" "F.Paste")
			(net "P3V3_EN_LV")
			(options
				(clearance outline)
				(anchor circle)
			)
			(primitives
				(gr_poly
					(pts
						(arc
							(start -0.1778 0.5715)
							(mid -0.321484 0.511984)
							(end -0.381 0.3683)
						)
						(arc
							(start -0.381 -0.3683)
							(mid -0.321484 -0.511984)
							(end -0.1778 -0.5715)
						)
						(arc
							(start 0.1778 -0.5715)
							(mid 0.321484 -0.511984)
							(end 0.381 -0.3683)
						)
						(arc
							(start 0.381 0.3683)
							(mid 0.321484 0.511984)
							(end 0.1778 0.5715)
						)
					)
					(width 0)
					(fill yes)
				)
			)
		)
		(pad "G" smd custom
			(at -0.98425 0.9525 270)
			(size 0.1905 0.1905)
			(layers "F.Cu" "F.Mask" "F.Paste")
			(net "P3V3_EN_G")
			(options
				(clearance outline)
				(anchor circle)
			)
			(primitives
				(gr_poly
					(pts
						(arc
							(start -0.1778 0.5715)
							(mid -0.321484 0.511984)
							(end -0.381 0.3683)
						)
						(arc
							(start -0.381 -0.3683)
							(mid -0.321484 -0.511984)
							(end -0.1778 -0.5715)
						)
						(arc
							(start 0.1778 -0.5715)
							(mid 0.321484 -0.511984)
							(end 0.381 -0.3683)
						)
						(arc
							(start 0.381 0.3683)
							(mid 0.321484 0.511984)
							(end 0.1778 0.5715)
						)
					)
					(width 0)
					(fill yes)
				)
			)
		)
		(pad "S" smd custom
			(at 0.98425 0.9525 270)
			(size 0.1905 0.1905)
			(layers "F.Cu" "F.Mask" "F.Paste")
			(net "P3V3_EN_B")
			(options
				(clearance outline)
				(anchor circle)
			)
			(primitives
				(gr_poly
					(pts
						(arc
							(start -0.1778 0.5715)
							(mid -0.321484 0.511984)
							(end -0.381 0.3683)
						)
						(arc
							(start -0.381 -0.3683)
							(mid -0.321484 -0.511984)
							(end -0.1778 -0.5715)
						)
						(arc
							(start 0.1778 -0.5715)
							(mid 0.321484 -0.511984)
							(end 0.381 -0.3683)
						)
						(arc
							(start 0.381 0.3683)
							(mid 0.321484 0.511984)
							(end 0.1778 0.5715)
						)
					)
					(width 0)
					(fill yes)
				)
			)
		)
	)
	(footprint ""
		(layer "F.Cu")
		(at 328.549 -114.3)
		(property "Reference" "PC21"
			(at 0 0 0)
			(layer "F.SilkS")
			(hide yes)
			(effects
				(font
					(size 1.27 1.27)
				)
			)
		)
		(property "Value" "SC22U25V5MX-GP"
			(at -0.0762 -6.1214 0)
			(unlocked yes)
			(layer "F.Fab")
			(hide yes)
			(effects
				(font
					(size 1.016 1.016)
					(thickness 0.1524)
				)
			)
		)
		(property "Device Type" "C805H58"
			(at -0.0762 -8.1534 0)
			(unlocked yes)
			(layer "F.Fab")
			(hide yes)
			(effects
				(font
					(size 1.016 1.016)
					(thickness 0.1524)
				)
			)
		)
		(duplicate_pad_numbers_are_jumpers no)
		(fp_line
			(start 0.635 0)
			(end -0.635 0)
			(stroke
				(width 0.508)
				(type default)
			)
			(layer "F.SilkS")
		)
		(fp_rect
			(start -0.9652 1.778)
			(end 0.9652 -1.778)
			(stroke
				(width 0)
				(type default)
			)
			(fill no)
			(layer "F.CrtYd")
		)
		(fp_poly
			(pts
				(xy -0.9652 -1.778) (xy 0.9652 -1.778) (xy 0.9652 1.778) (xy -0.9652 1.778)
			)
			(stroke
				(width 0)
				(type default)
			)
			(fill no)
			(layer "F.Fab")
		)
		(pad "1" smd rect
			(at 0 -0.9652)
			(size 1.397 1.143)
			(layers "F.Cu" "F.Mask" "F.Paste")
			(net "P3V3_STBY_VIN")
		)
		(pad "2" smd rect
			(at 0 0.9652)
			(size 1.397 1.143)
			(layers "F.Cu" "F.Mask" "F.Paste")
			(net "GND")
		)
	)
	(footprint ""
		(layer "F.Cu")
		(at 131.135882 -81.147158)
		(property "Reference" "SC1091"
			(at 0 0 0)
			(layer "F.SilkS")
			(hide yes)
			(effects
				(font
					(size 1.27 1.27)
				)
			)
		)
		(property "Value" "SCD01U10V1KX-GP"
			(at -2.8321 -1.7399 0)
			(unlocked yes)
			(layer "F.Fab")
			(hide yes)
			(effects
				(font
					(size 1.016 1.016)
					(thickness 0.1524)
				)
			)
		)
		(property "Device Type" "C0201H13"
			(at -2.8321 -3.2639 0)
			(unlocked yes)
			(layer "F.Fab")
			(hide yes)
			(effects
				(font
					(size 1.016 1.016)
					(thickness 0.1524)
				)
			)
		)
		(duplicate_pad_numbers_are_jumpers no)
		(fp_rect
			(start -0.2794 0.6477)
			(end 0.2794 -0.6477)
			(stroke
				(width 0)
				(type default)
			)
			(fill no)
			(layer "F.CrtYd")
		)
		(fp_rect
			(start -0.2794 0.6477)
			(end 0.2794 -0.6477)
			(stroke
				(width 0)
				(type default)
			)
			(fill no)
			(layer "F.Fab")
		)
		(pad "1" smd custom
			(at 0 -0.2794)
			(size 0.0762 0.0762)
			(layers "F.Cu" "F.Mask" "F.Paste")
			(net "SAS_HDD_TX12_N")
			(options
				(clearance outline)
				(anchor circle)
			)
			(primitives
				(gr_poly
					(pts
						(arc
							(start 0.1524 -0.127)
							(mid 0.137521 -0.162921)
							(end 0.1016 -0.1778)
						)
						(arc
							(start -0.1016 -0.1778)
							(mid -0.137521 -0.162921)
							(end -0.1524 -0.127)
						)
						(arc
							(start -0.1524 0.127)
							(mid -0.137521 0.162921)
							(end -0.1016 0.1778)
						)
						(arc
							(start 0.1016 0.1778)
							(mid 0.137521 0.162921)
							(end 0.1524 0.127)
						)
					)
					(width 0)
					(fill yes)
				)
			)
		)
		(pad "2" smd custom
			(at 0 0.2794)
			(size 0.0762 0.0762)
			(layers "F.Cu" "F.Mask" "F.Paste")
			(net "3008_SAS_RX_N0")
			(options
				(clearance outline)
				(anchor circle)
			)
			(primitives
				(gr_poly
					(pts
						(arc
							(start 0.1524 -0.127)
							(mid 0.137521 -0.162921)
							(end 0.1016 -0.1778)
						)
						(arc
							(start -0.1016 -0.1778)
							(mid -0.137521 -0.162921)
							(end -0.1524 -0.127)
						)
						(arc
							(start -0.1524 0.127)
							(mid -0.137521 0.162921)
							(end -0.1016 0.1778)
						)
						(arc
							(start 0.1016 0.1778)
							(mid 0.137521 0.162921)
							(end 0.1524 0.127)
						)
					)
					(width 0)
					(fill yes)
				)
			)
		)
	)
	(footprint ""
		(layer "F.Cu")
		(at 284.607 -162.433)
		(property "Reference" "TP136"
			(at 0 0 0)
			(layer "F.SilkS")
			(hide yes)
			(effects
				(font
					(size 1.27 1.27)
				)
			)
		)
		(property "Value" "TPAD28"
			(at 0.0127 -1.8034 0)
			(unlocked yes)
			(layer "F.Fab")
			(hide yes)
			(effects
				(font
					(size 1.016 1.016)
					(thickness 0.1524)
				)
			)
		)
		(property "Device Type" "TPAD28"
			(at 0.0127 -3.3274 0)
			(unlocked yes)
			(layer "F.Fab")
			(hide yes)
			(effects
				(font
					(size 1.016 1.016)
					(thickness 0.1524)
				)
			)
		)
		(duplicate_pad_numbers_are_jumpers no)
		(fp_poly
			(pts
				(arc
					(start 0.3556 0)
					(mid -0.3556 0)
					(end 0.3556 0)
				)
			)
			(stroke
				(width 0)
				(type default)
			)
			(fill no)
			(layer "F.CrtYd")
		)
		(fp_poly
			(pts
				(arc
					(start 0.6096 0)
					(mid -0.6096 0)
					(end 0.6096 0)
				)
			)
			(stroke
				(width 0)
				(type default)
			)
			(fill no)
			(layer "F.Fab")
		)
		(pad "1" smd circle
			(at 0 0)
			(size 0.7112 0.7112)
			(layers "F.Cu" "F.Mask" "F.Paste")
			(net "TP_BMC_GPIOF5")
		)
	)
	(footprint ""
		(layer "F.Cu")
		(at 343.183718 -142.852648 90)
		(property "Reference" "C8090"
			(at 0 0 90)
			(layer "F.SilkS")
			(hide yes)
			(effects
				(font
					(size 1.27 1.27)
				)
			)
		)
		(property "Value" "SC18P50V3JN-1-GP"
			(at 0 -2.8194 90)
			(unlocked yes)
			(layer "F.Fab")
			(hide yes)
			(effects
				(font
					(size 1.016 1.016)
					(thickness 0.1524)
				)
			)
		)
		(property "Device Type" "C603"
			(at 0 -4.3434 90)
			(unlocked yes)
			(layer "F.Fab")
			(hide yes)
			(effects
				(font
					(size 1.016 1.016)
					(thickness 0.1524)
				)
			)
		)
		(duplicate_pad_numbers_are_jumpers no)
		(fp_line
			(start 0.508 0)
			(end -0.508 0)
			(stroke
				(width 0.2032)
				(type default)
			)
			(layer "F.SilkS")
		)
		(fp_rect
			(start -0.5842 1.3335)
			(end 0.5842 -1.3335)
			(stroke
				(width 0)
				(type default)
			)
			(fill no)
			(layer "F.CrtYd")
		)
		(fp_rect
			(start -0.5842 1.3335)
			(end 0.5842 -1.3335)
			(stroke
				(width 0)
				(type default)
			)
			(fill no)
			(layer "F.Fab")
		)
		(pad "1" smd custom
			(at 0 -0.762 90)
			(size 0.2159 0.2159)
			(layers "F.Cu" "F.Mask" "F.Paste")
			(net "USB_HUB_XTAL_IN")
			(options
				(clearance outline)
				(anchor circle)
			)
			(primitives
				(gr_poly
					(pts
						(arc
							(start -0.3302 -0.4318)
							(mid -0.402042 -0.402042)
							(end -0.4318 -0.3302)
						)
						(arc
							(start -0.4318 0.3302)
							(mid -0.402042 0.402042)
							(end -0.3302 0.4318)
						)
						(arc
							(start 0.3302 0.4318)
							(mid 0.402042 0.402042)
							(end 0.4318 0.3302)
						)
						(arc
							(start 0.4318 -0.3302)
							(mid 0.402042 -0.402042)
							(end 0.3302 -0.4318)
						)
					)
					(width 0)
					(fill yes)
				)
			)
		)
		(pad "2" smd custom
			(at 0 0.762 90)
			(size 0.2159 0.2159)
			(layers "F.Cu" "F.Mask" "F.Paste")
			(net "GND")
			(options
				(clearance outline)
				(anchor circle)
			)
			(primitives
				(gr_poly
					(pts
						(arc
							(start -0.3302 -0.4318)
							(mid -0.402042 -0.402042)
							(end -0.4318 -0.3302)
						)
						(arc
							(start -0.4318 0.3302)
							(mid -0.402042 0.402042)
							(end -0.3302 0.4318)
						)
						(arc
							(start 0.3302 0.4318)
							(mid 0.402042 0.402042)
							(end 0.4318 0.3302)
						)
						(arc
							(start 0.4318 -0.3302)
							(mid 0.402042 -0.402042)
							(end 0.3302 -0.4318)
						)
					)
					(width 0)
					(fill yes)
				)
			)
		)
	)
	(footprint ""
		(layer "F.Cu")
		(at 320.294 -197.866 90)
		(property "Reference" "R561"
			(at 0 0 90)
			(layer "F.SilkS")
			(hide yes)
			(effects
				(font
					(size 1.27 1.27)
				)
			)
		)
		(property "Value" "10KR2F-2-GP"
			(at 0.064008 -3.993896 90)
			(unlocked yes)
			(layer "F.Fab")
			(hide yes)
			(effects
				(font
					(size 1.016 1.016)
					(thickness 0.1524)
				)
			)
		)
		(property "Device Type" "R402H16"
			(at 0.064008 -5.517896 90)
			(unlocked yes)
			(layer "F.Fab")
			(hide yes)
			(effects
				(font
					(size 1.016 1.016)
					(thickness 0.1524)
				)
			)
		)
		(duplicate_pad_numbers_are_jumpers no)
		(fp_line
			(start 0.508 -0.9398)
			(end -0.508 -0.9398)
			(stroke
				(width 0.1524)
				(type default)
			)
			(layer "F.SilkS")
		)
		(fp_line
			(start -0.508 -0.9398)
			(end -0.508 0.9398)
			(stroke
				(width 0.1524)
				(type default)
			)
			(layer "F.SilkS")
		)
		(fp_rect
			(start -0.508 0.9398)
			(end 0.508 -0.9398)
			(stroke
				(width 0)
				(type default)
			)
			(fill no)
			(layer "F.CrtYd")
		)
		(fp_rect
			(start -0.508 0.9398)
			(end 0.508 -0.9398)
			(stroke
				(width 0)
				(type default)
			)
			(fill no)
			(layer "F.Fab")
		)
		(pad "1" smd custom
			(at 0 -0.4445 90)
			(size 0.1397 0.1397)
			(layers "F.Cu" "F.Mask" "F.Paste")
			(net "BMC_JTAG_L_EN")
			(options
				(clearance outline)
				(anchor circle)
			)
			(primitives
				(gr_poly
					(pts
						(arc
							(start -0.1778 -0.2794)
							(mid -0.249642 -0.249642)
							(end -0.2794 -0.1778)
						)
						(arc
							(start -0.2794 0.1778)
							(mid -0.249642 0.249642)
							(end -0.1778 0.2794)
						)
						(arc
							(start 0.1778 0.2794)
							(mid 0.249642 0.249642)
							(end 0.2794 0.1778)
						)
						(arc
							(start 0.2794 -0.1778)
							(mid 0.249642 -0.249642)
							(end 0.1778 -0.2794)
						)
					)
					(width 0)
					(fill yes)
				)
			)
		)
		(pad "2" smd custom
			(at 0 0.4445 90)
			(size 0.1397 0.1397)
			(layers "F.Cu" "F.Mask" "F.Paste")
			(net "GND")
			(options
				(clearance outline)
				(anchor circle)
			)
			(primitives
				(gr_poly
					(pts
						(arc
							(start -0.1778 -0.2794)
							(mid -0.249642 -0.249642)
							(end -0.2794 -0.1778)
						)
						(arc
							(start -0.2794 0.1778)
							(mid -0.249642 0.249642)
							(end -0.1778 0.2794)
						)
						(arc
							(start 0.1778 0.2794)
							(mid 0.249642 0.249642)
							(end 0.2794 0.1778)
						)
						(arc
							(start 0.2794 -0.1778)
							(mid 0.249642 -0.249642)
							(end 0.1778 -0.2794)
						)
					)
					(width 0)
					(fill yes)
				)
			)
		)
	)
	(footprint ""
		(layer "F.Cu")
		(at 89.643966 -61.468)
		(property "Reference" "STP31"
			(at 0 0 0)
			(layer "F.SilkS")
			(hide yes)
			(effects
				(font
					(size 1.27 1.27)
				)
			)
		)
		(property "Value" "TPAD28"
			(at 0.0127 -1.8034 0)
			(unlocked yes)
			(layer "F.Fab")
			(hide yes)
			(effects
				(font
					(size 1.016 1.016)
					(thickness 0.1524)
				)
			)
		)
		(property "Device Type" "TPAD28"
			(at 0.0127 -3.3274 0)
			(unlocked yes)
			(layer "F.Fab")
			(hide yes)
			(effects
				(font
					(size 1.016 1.016)
					(thickness 0.1524)
				)
			)
		)
		(duplicate_pad_numbers_are_jumpers no)
		(fp_poly
			(pts
				(arc
					(start 0.3556 0)
					(mid -0.3556 0)
					(end 0.3556 0)
				)
			)
			(stroke
				(width 0)
				(type default)
			)
			(fill no)
			(layer "F.CrtYd")
		)
		(fp_poly
			(pts
				(arc
					(start 0.6096 0)
					(mid -0.6096 0)
					(end 0.6096 0)
				)
			)
			(stroke
				(width 0)
				(type default)
			)
			(fill no)
			(layer "F.Fab")
		)
		(pad "1" smd circle
			(at 0 0)
			(size 0.7112 0.7112)
			(layers "F.Cu" "F.Mask" "F.Paste")
			(net "ICE0_TMS")
		)
	)
	(footprint ""
		(layer "F.Cu")
		(at 279.654 -108.712 -90)
		(property "Reference" "PR175"
			(at 0 0 270)
			(layer "F.SilkS")
			(hide yes)
			(effects
				(font
					(size 1.27 1.27)
				)
			)
		)
		(property "Value" "20KR2F-L-GP"
			(at 0.064008 -3.993896 270)
			(unlocked yes)
			(layer "F.Fab")
			(hide yes)
			(effects
				(font
					(size 1.016 1.016)
					(thickness 0.1524)
				)
			)
		)
		(property "Device Type" "R402H16"
			(at 0.064008 -5.517896 270)
			(unlocked yes)
			(layer "F.Fab")
			(hide yes)
			(effects
				(font
					(size 1.016 1.016)
					(thickness 0.1524)
				)
			)
		)
		(duplicate_pad_numbers_are_jumpers no)
		(fp_line
			(start -0.508 -0.9398)
			(end -0.508 0.9398)
			(stroke
				(width 0.1524)
				(type default)
			)
			(layer "F.SilkS")
		)
		(fp_line
			(start 0.508 -0.9398)
			(end -0.508 -0.9398)
			(stroke
				(width 0.1524)
				(type default)
			)
			(layer "F.SilkS")
		)
		(fp_rect
			(start -0.508 0.9398)
			(end 0.508 -0.9398)
			(stroke
				(width 0)
				(type default)
			)
			(fill no)
			(layer "F.CrtYd")
		)
		(fp_rect
			(start -0.508 0.9398)
			(end 0.508 -0.9398)
			(stroke
				(width 0)
				(type default)
			)
			(fill no)
			(layer "F.Fab")
		)
		(pad "1" smd custom
			(at 0 -0.4445 270)
			(size 0.1397 0.1397)
			(layers "F.Cu" "F.Mask" "F.Paste")
			(net "P12V")
			(options
				(clearance outline)
				(anchor circle)
			)
			(primitives
				(gr_poly
					(pts
						(arc
							(start -0.1778 -0.2794)
							(mid -0.249642 -0.249642)
							(end -0.2794 -0.1778)
						)
						(arc
							(start -0.2794 0.1778)
							(mid -0.249642 0.249642)
							(end -0.1778 0.2794)
						)
						(arc
							(start 0.1778 0.2794)
							(mid 0.249642 0.249642)
							(end 0.2794 0.1778)
						)
						(arc
							(start 0.2794 -0.1778)
							(mid 0.249642 -0.249642)
							(end 0.1778 -0.2794)
						)
					)
					(width 0)
					(fill yes)
				)
			)
		)
		(pad "2" smd custom
			(at 0 0.4445 270)
			(size 0.1397 0.1397)
			(layers "F.Cu" "F.Mask" "F.Paste")
			(net "P1V8_C_EN_LV")
			(options
				(clearance outline)
				(anchor circle)
			)
			(primitives
				(gr_poly
					(pts
						(arc
							(start -0.1778 -0.2794)
							(mid -0.249642 -0.249642)
							(end -0.2794 -0.1778)
						)
						(arc
							(start -0.2794 0.1778)
							(mid -0.249642 0.249642)
							(end -0.1778 0.2794)
						)
						(arc
							(start 0.1778 0.2794)
							(mid 0.249642 0.249642)
							(end 0.2794 0.1778)
						)
						(arc
							(start 0.2794 -0.1778)
							(mid 0.249642 -0.249642)
							(end 0.1778 -0.2794)
						)
					)
					(width 0)
					(fill yes)
				)
			)
		)
	)
)
